# S9S_MB_2U (Grand Teton) — schematic netlist excerpt (pin names and nets, part order shuffled) for the footprints in the layout excerpt that follows; sources: Cadence DE-HDL packaged netlist, KiCad conversion of 03242023_DA0F0TMBIJ0_F0T_Motherboard_J_brd_V01_OCP.brd

R2694  Q_RES  1K 1% CHIP  pkg 0402LF  page 227 : A = TCA9539_0_ADD1 ; B = GND

PR2532  Q_SP_RES4P  0.0003 1% EMPTY  pkg R2725_4P  page 304
  \1a\  = P12V_PSU
  \1b\  = P12V_HSC_SENSE2_R2_P
  \2a\  = P12V_MAIN_R
  \2b\  = P12V_HSC_SENSE2_R2_N

(kicad_pcb
	(version 20260206)
	(generator "pcbnew")
	(generator_version "10.0")
	(general
		(thickness 1.6)
		(legacy_teardrops no)
	)
	(paper "A4")
	(title_block
		(title "03242023_DA0F0TMBIJ0_F0T_Motherboard_J_brd_V01_OCP.brd")
		(comment 1 "Grand Teton / footprints 2476-2477 of 6105")
	)
	(layers
		(0 "F.Cu" signal "TOP")
		(4 "In1.Cu" signal "GND")
		(6 "In2.Cu" signal "IN1")
		(8 "In3.Cu" signal "GND1")
		(10 "In4.Cu" signal "IN2")
		(12 "In5.Cu" signal "GND2")
		(14 "In6.Cu" signal "IN3")
		(16 "In7.Cu" signal "GND3")
		(18 "In8.Cu" signal "VCC")
		(20 "In9.Cu" signal "VCC1")
		(22 "In10.Cu" signal "GND4")
		(24 "In11.Cu" signal "IN4")
		(26 "In12.Cu" signal "GND5")
		(28 "In13.Cu" signal "IN5")
		(30 "In14.Cu" signal "GND6")
		(32 "In15.Cu" signal "IN6")
		(34 "In16.Cu" signal "GND7")
		(2 "B.Cu" signal "BOTTOM")
		(9 "F.Adhes" user "F.Adhesive")
		(11 "B.Adhes" user "B.Adhesive")
		(13 "F.Paste" user "Package Geometry/Pastemask Top")
		(15 "B.Paste" user "Package Geometry/Pastemask Bottom")
		(5 "F.SilkS" user "Ref Des/Silkscreen Top")
		(7 "B.SilkS" user "Ref Des/Silkscreen Bottom")
		(1 "F.Mask" user "Board Geometry/Soldermask Top")
		(3 "B.Mask" user "Board Geometry/Soldermask Bottom")
		(17 "Dwgs.User" user "User.Drawings")
		(19 "Cmts.User" user "User.Comments")
		(21 "Eco1.User" user "User.Eco1")
		(23 "Eco2.User" user "User.Eco2")
		(25 "Edge.Cuts" user "Board Geometry/Outline")
		(27 "Margin" user)
		(31 "F.CrtYd" user "Package Geometry/Place Bound Top")
		(29 "B.CrtYd" user "Package Geometry/Place Bound Bottom")
		(35 "F.Fab" user "Ref Des/Assembly Top")
		(33 "B.Fab" user "Ref Des/Assembly Bottom")
	)
	(footprint ""
		(layer "F.Cu")
		(at 268.833092 -407.416 -90)
		(property "Reference" "PR2532"
			(at 0 0 270)
			(layer "F.SilkS")
			(hide yes)
			(effects
				(font
					(size 1.27 1.27)
				)
			)
		)
		(property "Value" ""
			(at 0 0 270)
			(layer "F.Fab")
			(effects
				(font
					(size 1.27 1.27)
				)
			)
		)
		(duplicate_pad_numbers_are_jumpers no)
		(fp_line
			(start -3.9878 3.5814)
			(end -3.9878 -3.5814)
			(stroke
				(width 0.1524)
				(type default)
			)
			(layer "F.SilkS")
		)
		(fp_line
			(start 3.9878 3.5814)
			(end -3.9878 3.5814)
			(stroke
				(width 0.1524)
				(type default)
			)
			(layer "F.SilkS")
		)
		(fp_line
			(start -3.9878 -3.5814)
			(end 3.9878 -3.5814)
			(stroke
				(width 0.1524)
				(type default)
			)
			(layer "F.SilkS")
		)
		(fp_line
			(start 3.9878 -3.5814)
			(end 3.9878 3.5814)
			(stroke
				(width 0.1524)
				(type default)
			)
			(layer "F.SilkS")
		)
		(fp_line
			(start -3.5306 3.353054)
			(end -3.5306 -3.353054)
			(stroke
				(width 0.1)
				(type default)
			)
			(layer "F.Fab")
		)
		(fp_line
			(start 3.5306 3.353054)
			(end -3.5306 3.353054)
			(stroke
				(width 0.1)
				(type default)
			)
			(layer "F.Fab")
		)
		(fp_line
			(start -3.5306 -3.353054)
			(end 3.5306 -3.353054)
			(stroke
				(width 0.1)
				(type default)
			)
			(layer "F.Fab")
		)
		(fp_line
			(start 3.5306 -3.353054)
			(end 3.5306 3.353054)
			(stroke
				(width 0.1)
				(type default)
			)
			(layer "F.Fab")
		)
		(pad "1A" smd rect
			(at -2.249932 0 90)
			(size 3.2004 6.858)
			(layers "F.Cu" "F.Mask" "F.Paste")
			(net "P12V_PSU")
		)
		(pad "1B" smd rect
			(at -0.776732 0 270)
			(size 0.254 0.508)
			(layers "F.Cu" "F.Mask" "F.Paste")
			(net "P12V_HSC_SENSE2_R2_P")
		)
		(pad "2A" smd rect
			(at 2.249932 0 90)
			(size 3.2004 6.858)
			(layers "F.Cu" "F.Mask" "F.Paste")
			(net "P12V_MAIN_R")
		)
		(pad "2B" smd rect
			(at 0.776732 0 270)
			(size 0.254 0.508)
			(layers "F.Cu" "F.Mask" "F.Paste")
			(net "P12V_HSC_SENSE2_R2_N")
		)
	)
	(footprint ""
		(layer "F.Cu")
		(at 13.800582 -408.516836 -90)
		(property "Reference" "R2694"
			(at 0 0 270)
			(layer "F.SilkS")
			(hide yes)
			(effects
				(font
					(size 1.27 1.27)
				)
			)
		)
		(property "Value" ""
			(at 0 0 270)
			(layer "F.Fab")
			(effects
				(font
					(size 1.27 1.27)
				)
			)
		)
		(duplicate_pad_numbers_are_jumpers no)
		(fp_line
			(start -0.7874 0.4064)
			(end -0.7874 -0.4064)
			(stroke
				(width 0.1524)
				(type default)
			)
			(layer "F.SilkS")
		)
		(fp_line
			(start 0.7874 0.4064)
			(end -0.7874 0.4064)
			(stroke
				(width 0.1524)
				(type default)
			)
			(layer "F.SilkS")
		)
		(fp_line
			(start -0.7874 -0.4064)
			(end 0.7874 -0.4064)
			(stroke
				(width 0.1524)
				(type default)
			)
			(layer "F.SilkS")
		)
		(fp_line
			(start 0.7874 -0.4064)
			(end 0.7874 0.4064)
			(stroke
				(width 0.1524)
				(type default)
			)
			(layer "F.SilkS")
		)
		(fp_line
			(start -0.67945 0.3048)
			(end -0.67945 -0.305054)
			(stroke
				(width 0.1)
				(type default)
			)
			(layer "F.Fab")
		)
		(fp_line
			(start -0.12065 0.3048)
			(end -0.67945 0.3048)
			(stroke
				(width 0.1)
				(type default)
			)
			(layer "F.Fab")
		)
		(fp_line
			(start 0.120396 0.3048)
			(end 0.120396 0.2794)
			(stroke
				(width 0.1)
				(type default)
			)
			(layer "F.Fab")
		)
		(fp_line
			(start 0.67945 0.3048)
			(end 0.120396 0.3048)
			(stroke
				(width 0.1)
				(type default)
			)
			(layer "F.Fab")
		)
		(fp_line
			(start -0.12065 0.2794)
			(end -0.12065 0.3048)
			(stroke
				(width 0.1)
				(type default)
			)
			(layer "F.Fab")
		)
		(fp_line
			(start 0.120396 0.2794)
			(end -0.12065 0.2794)
			(stroke
				(width 0.1)
				(type default)
			)
			(layer "F.Fab")
		)
		(fp_line
			(start -0.12065 -0.2794)
			(end 0.12065 -0.2794)
			(stroke
				(width 0.1)
				(type default)
			)
			(layer "F.Fab")
		)
		(fp_line
			(start 0.12065 -0.2794)
			(end 0.12065 -0.3048)
			(stroke
				(width 0.1)
				(type default)
			)
			(layer "F.Fab")
		)
		(fp_line
			(start 0.12065 -0.3048)
			(end 0.67945 -0.3048)
			(stroke
				(width 0.1)
				(type default)
			)
			(layer "F.Fab")
		)
		(fp_line
			(start 0.67945 -0.3048)
			(end 0.67945 0.3048)
			(stroke
				(width 0.1)
				(type default)
			)
			(layer "F.Fab")
		)
		(fp_line
			(start -0.67945 -0.305054)
			(end -0.12065 -0.305054)
			(stroke
				(width 0.1)
				(type default)
			)
			(layer "F.Fab")
		)
		(fp_line
			(start -0.12065 -0.305054)
			(end -0.12065 -0.2794)
			(stroke
				(width 0.1)
				(type default)
			)
			(layer "F.Fab")
		)
		(pad "1" smd circle
			(at -0.40005 0 270)
			(size 0 0)
			(layers "F.Cu" "F.Mask" "F.Paste")
			(net "TCA9539_0_ADD1")
		)
		(pad "2" smd circle
			(at 0.40005 0 270)
			(size 0 0)
			(layers "F.Cu" "F.Mask" "F.Paste")
			(net "GND")
		)
	)
)
